(kicad_pcb
	(version 20260206)
	(generator "pcbnew")
	(generator_version "10.0")
	(general
		(thickness 1.6)
		(legacy_teardrops no)
	)
	(paper "A4")
	(title_block
		(title "pdpb — Lightning_PDPB_BRD.brd")
		(comment 1 "Lightning (Wiwynn / Facebook NVMe JBOF) / footprints 58-65 of 1140")
	)
	(layers
		(0 "F.Cu" signal "TOP")
		(4 "In1.Cu" signal "L2GND")
		(6 "In2.Cu" signal "L3")
		(8 "In3.Cu" signal "L4VCC")
		(10 "In4.Cu" signal "L5VCC")
		(12 "In5.Cu" signal "L6")
		(14 "In6.Cu" signal "L7GND")
		(2 "B.Cu" signal "BOTTOM")
		(9 "F.Adhes" user "F.Adhesive")
		(11 "B.Adhes" user "B.Adhesive")
		(13 "F.Paste" user "Package Geometry/Pastemask Top")
		(15 "B.Paste" user "Package Geometry/Pastemask Bottom")
		(5 "F.SilkS" user "Ref Des/Silkscreen Top")
		(7 "B.SilkS" user "Ref Des/Silkscreen Bottom")
		(1 "F.Mask" user "Board Geometry/Soldermask Top")
		(3 "B.Mask" user "Board Geometry/Soldermask Bottom")
		(17 "Dwgs.User" user "User.Drawings")
		(19 "Cmts.User" user "User.Comments")
		(21 "Eco1.User" user "User.Eco1")
		(23 "Eco2.User" user "User.Eco2")
		(25 "Edge.Cuts" user "Board Geometry/Outline")
		(27 "Margin" user)
		(31 "F.CrtYd" user "Package Geometry/Place Bound Top")
		(29 "B.CrtYd" user "Package Geometry/Place Bound Bottom")
		(35 "F.Fab" user "Ref Des/Assembly Top")
		(33 "B.Fab" user "Ref Des/Assembly Bottom")
	)
	(footprint ""
		(layer "F.Cu")
		(at 70.739 -358.521 90)
		(property "Reference" "SR980"
			(at 0 0 90)
			(layer "F.SilkS")
			(hide yes)
			(effects
				(font
					(size 1.27 1.27)
				)
			)
		)
		(property "Value" "2KR2F-3-GP"
			(at 0.064008 -3.993896 90)
			(unlocked yes)
			(layer "F.Fab")
			(hide yes)
			(effects
				(font
					(size 1.016 1.016)
					(thickness 0.1524)
				)
			)
		)
		(property "Device Type" "R402H16"
			(at 0.064008 -5.517896 90)
			(unlocked yes)
			(layer "F.Fab")
			(hide yes)
			(effects
				(font
					(size 1.016 1.016)
					(thickness 0.1524)
				)
			)
		)
		(duplicate_pad_numbers_are_jumpers no)
		(fp_line
			(start 0.508 -0.9398)
			(end -0.508 -0.9398)
			(stroke
				(width 0.1524)
				(type default)
			)
			(layer "F.SilkS")
		)
		(fp_line
			(start -0.508 -0.9398)
			(end -0.508 0.9398)
			(stroke
				(width 0.1524)
				(type default)
			)
			(layer "F.SilkS")
		)
		(fp_rect
			(start -0.508 0.9398)
			(end 0.508 -0.9398)
			(stroke
				(width 0)
				(type default)
			)
			(fill no)
			(layer "F.CrtYd")
		)
		(fp_rect
			(start -0.508 0.9398)
			(end 0.508 -0.9398)
			(stroke
				(width 0)
				(type default)
			)
			(fill no)
			(layer "F.Fab")
		)
		(pad "1" smd custom
			(at 0 -0.4445 90)
			(size 0.1397 0.1397)
			(layers "F.Cu" "F.Mask" "F.Paste")
			(net "P3V3")
			(options
				(clearance outline)
				(anchor circle)
			)
			(primitives
				(gr_poly
					(pts
						(arc
							(start -0.1778 -0.2794)
							(mid -0.249642 -0.249642)
							(end -0.2794 -0.1778)
						)
						(arc
							(start -0.2794 0.1778)
							(mid -0.249642 0.249642)
							(end -0.1778 0.2794)
						)
						(arc
							(start 0.1778 0.2794)
							(mid 0.249642 0.249642)
							(end 0.2794 0.1778)
						)
						(arc
							(start 0.2794 -0.1778)
							(mid 0.249642 -0.249642)
							(end 0.1778 -0.2794)
						)
					)
					(width 0)
					(fill yes)
				)
			)
		)
		(pad "2" smd custom
			(at 0 0.4445 90)
			(size 0.1397 0.1397)
			(layers "F.Cu" "F.Mask" "F.Paste")
			(net "SCL_DR7")
			(options
				(clearance outline)
				(anchor circle)
			)
			(primitives
				(gr_poly
					(pts
						(arc
							(start -0.1778 -0.2794)
							(mid -0.249642 -0.249642)
							(end -0.2794 -0.1778)
						)
						(arc
							(start -0.2794 0.1778)
							(mid -0.249642 0.249642)
							(end -0.1778 0.2794)
						)
						(arc
							(start 0.1778 0.2794)
							(mid 0.249642 0.249642)
							(end 0.2794 0.1778)
						)
						(arc
							(start 0.2794 -0.1778)
							(mid 0.249642 -0.249642)
							(end 0.1778 -0.2794)
						)
					)
					(width 0)
					(fill yes)
				)
			)
		)
	)
	(footprint ""
		(layer "F.Cu")
		(at 207.391 -44.704 180)
		(property "Reference" "R327"
			(at 0 0 180)
			(layer "F.SilkS")
			(hide yes)
			(effects
				(font
					(size 1.27 1.27)
				)
			)
		)
		(property "Value" "4K7R2F-GP"
			(at 0.064008 -3.993896 180)
			(unlocked yes)
			(layer "F.Fab")
			(hide yes)
			(effects
				(font
					(size 1.016 1.016)
					(thickness 0.1524)
				)
			)
		)
		(property "Device Type" "R402H16"
			(at 0.064008 -5.517896 180)
			(unlocked yes)
			(layer "F.Fab")
			(hide yes)
			(effects
				(font
					(size 1.016 1.016)
					(thickness 0.1524)
				)
			)
		)
		(duplicate_pad_numbers_are_jumpers no)
		(fp_line
			(start 0.508 -0.9398)
			(end -0.508 -0.9398)
			(stroke
				(width 0.1524)
				(type default)
			)
			(layer "F.SilkS")
		)
		(fp_line
			(start -0.508 -0.9398)
			(end -0.508 0.9398)
			(stroke
				(width 0.1524)
				(type default)
			)
			(layer "F.SilkS")
		)
		(fp_rect
			(start -0.508 0.9398)
			(end 0.508 -0.9398)
			(stroke
				(width 0)
				(type default)
			)
			(fill no)
			(layer "F.CrtYd")
		)
		(fp_rect
			(start -0.508 0.9398)
			(end 0.508 -0.9398)
			(stroke
				(width 0)
				(type default)
			)
			(fill no)
			(layer "F.Fab")
		)
		(pad "1" smd custom
			(at 0 -0.4445 180)
			(size 0.1397 0.1397)
			(layers "F.Cu" "F.Mask" "F.Paste")
			(net "P3V3")
			(options
				(clearance outline)
				(anchor circle)
			)
			(primitives
				(gr_poly
					(pts
						(arc
							(start -0.1778 -0.2794)
							(mid -0.249642 -0.249642)
							(end -0.2794 -0.1778)
						)
						(arc
							(start -0.2794 0.1778)
							(mid -0.249642 0.249642)
							(end -0.1778 0.2794)
						)
						(arc
							(start 0.1778 0.2794)
							(mid 0.249642 0.249642)
							(end 0.2794 0.1778)
						)
						(arc
							(start 0.2794 -0.1778)
							(mid 0.249642 -0.249642)
							(end 0.1778 -0.2794)
						)
					)
					(width 0)
					(fill yes)
				)
			)
		)
		(pad "2" smd custom
			(at 0 0.4445 180)
			(size 0.1397 0.1397)
			(layers "F.Cu" "F.Mask" "F.Paste")
			(net "I2C_B_TMP3_A0")
			(options
				(clearance outline)
				(anchor circle)
			)
			(primitives
				(gr_poly
					(pts
						(arc
							(start -0.1778 -0.2794)
							(mid -0.249642 -0.249642)
							(end -0.2794 -0.1778)
						)
						(arc
							(start -0.2794 0.1778)
							(mid -0.249642 0.249642)
							(end -0.1778 0.2794)
						)
						(arc
							(start 0.1778 0.2794)
							(mid 0.249642 0.249642)
							(end 0.2794 0.1778)
						)
						(arc
							(start 0.2794 -0.1778)
							(mid 0.249642 -0.249642)
							(end 0.1778 -0.2794)
						)
					)
					(width 0)
					(fill yes)
				)
			)
		)
	)
	(footprint ""
		(layer "F.Cu")
		(at 245.491 -424.434 -90)
		(property "Reference" "C356"
			(at 0 0 270)
			(layer "F.SilkS")
			(hide yes)
			(effects
				(font
					(size 1.27 1.27)
				)
			)
		)
		(property "Value" "SC220P50V3JN-GP"
			(at 0 -2.8194 270)
			(unlocked yes)
			(layer "F.Fab")
			(hide yes)
			(effects
				(font
					(size 1.016 1.016)
					(thickness 0.1524)
				)
			)
		)
		(property "Device Type" "C603H36"
			(at 0 -4.3434 270)
			(unlocked yes)
			(layer "F.Fab")
			(hide yes)
			(effects
				(font
					(size 1.016 1.016)
					(thickness 0.1524)
				)
			)
		)
		(duplicate_pad_numbers_are_jumpers no)
		(fp_line
			(start 0.508 0)
			(end -0.508 0)
			(stroke
				(width 0.2032)
				(type default)
			)
			(layer "F.SilkS")
		)
		(fp_rect
			(start -0.5842 1.3335)
			(end 0.5842 -1.3335)
			(stroke
				(width 0)
				(type default)
			)
			(fill no)
			(layer "F.CrtYd")
		)
		(fp_rect
			(start -0.5842 1.3335)
			(end 0.5842 -1.3335)
			(stroke
				(width 0)
				(type default)
			)
			(fill no)
			(layer "F.Fab")
		)
		(pad "1" smd custom
			(at 0 -0.762 270)
			(size 0.2159 0.2159)
			(layers "F.Cu" "F.Mask" "F.Paste")
			(net "I2C_C_SCL")
			(options
				(clearance outline)
				(anchor circle)
			)
			(primitives
				(gr_poly
					(pts
						(arc
							(start -0.3302 -0.4318)
							(mid -0.402042 -0.402042)
							(end -0.4318 -0.3302)
						)
						(arc
							(start -0.4318 0.3302)
							(mid -0.402042 0.402042)
							(end -0.3302 0.4318)
						)
						(arc
							(start 0.3302 0.4318)
							(mid 0.402042 0.402042)
							(end 0.4318 0.3302)
						)
						(arc
							(start 0.4318 -0.3302)
							(mid 0.402042 -0.402042)
							(end 0.3302 -0.4318)
						)
					)
					(width 0)
					(fill yes)
				)
			)
		)
		(pad "2" smd custom
			(at 0 0.762 270)
			(size 0.2159 0.2159)
			(layers "F.Cu" "F.Mask" "F.Paste")
			(net "GND")
			(options
				(clearance outline)
				(anchor circle)
			)
			(primitives
				(gr_poly
					(pts
						(arc
							(start -0.3302 -0.4318)
							(mid -0.402042 -0.402042)
							(end -0.4318 -0.3302)
						)
						(arc
							(start -0.4318 0.3302)
							(mid -0.402042 0.402042)
							(end -0.3302 0.4318)
						)
						(arc
							(start 0.3302 0.4318)
							(mid 0.402042 0.402042)
							(end 0.4318 0.3302)
						)
						(arc
							(start 0.4318 -0.3302)
							(mid 0.402042 -0.402042)
							(end 0.3302 -0.4318)
						)
					)
					(width 0)
					(fill yes)
				)
			)
		)
	)
	(footprint ""
		(layer "F.Cu")
		(at 87.122 -215.519)
		(property "Reference" "C8913"
			(at 0 0 0)
			(layer "F.SilkS")
			(hide yes)
			(effects
				(font
					(size 1.27 1.27)
				)
			)
		)
		(property "Value" "SC1U10V2KX-7-GP"
			(at 1.1811 -2.7051 0)
			(unlocked yes)
			(layer "F.Fab")
			(hide yes)
			(effects
				(font
					(size 1.016 1.016)
					(thickness 0.1524)
				)
			)
		)
		(property "Device Type" "C402H22"
			(at 1.1811 -4.2291 0)
			(unlocked yes)
			(layer "F.Fab")
			(hide yes)
			(effects
				(font
					(size 1.016 1.016)
					(thickness 0.1524)
				)
			)
		)
		(duplicate_pad_numbers_are_jumpers no)
		(fp_rect
			(start -0.4318 0.9525)
			(end 0.4318 -0.9525)
			(stroke
				(width 0)
				(type default)
			)
			(fill no)
			(layer "F.CrtYd")
		)
		(fp_rect
			(start -0.4318 0.9525)
			(end 0.4318 -0.9525)
			(stroke
				(width 0)
				(type default)
			)
			(fill no)
			(layer "F.Fab")
		)
		(pad "1" smd custom
			(at 0 -0.4445)
			(size 0.1524 0.1524)
			(layers "F.Cu" "F.Mask" "F.Paste")
			(net "VDDA_3")
			(options
				(clearance outline)
				(anchor circle)
			)
			(primitives
				(gr_poly
					(pts
						(arc
							(start 0.3048 -0.2032)
							(mid 0.275042 -0.275042)
							(end 0.2032 -0.3048)
						)
						(arc
							(start -0.2032 -0.3048)
							(mid -0.275042 -0.275042)
							(end -0.3048 -0.2032)
						)
						(arc
							(start -0.3048 0.2032)
							(mid -0.275042 0.275042)
							(end -0.2032 0.3048)
						)
						(arc
							(start 0.2032 0.3048)
							(mid 0.275042 0.275042)
							(end 0.3048 0.2032)
						)
					)
					(width 0)
					(fill yes)
				)
			)
		)
		(pad "2" smd custom
			(at 0 0.4445)
			(size 0.1524 0.1524)
			(layers "F.Cu" "F.Mask" "F.Paste")
			(net "GND")
			(options
				(clearance outline)
				(anchor circle)
			)
			(primitives
				(gr_poly
					(pts
						(arc
							(start 0.3048 -0.2032)
							(mid 0.275042 -0.275042)
							(end 0.2032 -0.3048)
						)
						(arc
							(start -0.2032 -0.3048)
							(mid -0.275042 -0.275042)
							(end -0.3048 -0.2032)
						)
						(arc
							(start -0.3048 0.2032)
							(mid -0.275042 0.275042)
							(end -0.2032 0.3048)
						)
						(arc
							(start 0.2032 0.3048)
							(mid 0.275042 0.275042)
							(end 0.3048 0.2032)
						)
					)
					(width 0)
					(fill yes)
				)
			)
		)
	)
	(footprint ""
		(layer "F.Cu")
		(at 93.599 -93.853)
		(property "Reference" "C9517"
			(at 0 0 0)
			(layer "F.SilkS")
			(hide yes)
			(effects
				(font
					(size 1.27 1.27)
				)
			)
		)
		(property "Value" "SCD1U16V2KX-3GP"
			(at 1.1811 -2.7051 0)
			(unlocked yes)
			(layer "F.Fab")
			(hide yes)
			(effects
				(font
					(size 1.016 1.016)
					(thickness 0.1524)
				)
			)
		)
		(property "Device Type" "C402H22"
			(at 1.1811 -4.2291 0)
			(unlocked yes)
			(layer "F.Fab")
			(hide yes)
			(effects
				(font
					(size 1.016 1.016)
					(thickness 0.1524)
				)
			)
		)
		(duplicate_pad_numbers_are_jumpers no)
		(fp_rect
			(start -0.4318 0.9525)
			(end 0.4318 -0.9525)
			(stroke
				(width 0)
				(type default)
			)
			(fill no)
			(layer "F.CrtYd")
		)
		(fp_rect
			(start -0.4318 0.9525)
			(end 0.4318 -0.9525)
			(stroke
				(width 0)
				(type default)
			)
			(fill no)
			(layer "F.Fab")
		)
		(pad "1" smd custom
			(at 0 -0.4445)
			(size 0.1524 0.1524)
			(layers "F.Cu" "F.Mask" "F.Paste")
			(net "VDD_DIFF_4")
			(options
				(clearance outline)
				(anchor circle)
			)
			(primitives
				(gr_poly
					(pts
						(arc
							(start 0.3048 -0.2032)
							(mid 0.275042 -0.275042)
							(end 0.2032 -0.3048)
						)
						(arc
							(start -0.2032 -0.3048)
							(mid -0.275042 -0.275042)
							(end -0.3048 -0.2032)
						)
						(arc
							(start -0.3048 0.2032)
							(mid -0.275042 0.275042)
							(end -0.2032 0.3048)
						)
						(arc
							(start 0.2032 0.3048)
							(mid 0.275042 0.275042)
							(end 0.3048 0.2032)
						)
					)
					(width 0)
					(fill yes)
				)
			)
		)
		(pad "2" smd custom
			(at 0 0.4445)
			(size 0.1524 0.1524)
			(layers "F.Cu" "F.Mask" "F.Paste")
			(net "GND")
			(options
				(clearance outline)
				(anchor circle)
			)
			(primitives
				(gr_poly
					(pts
						(arc
							(start 0.3048 -0.2032)
							(mid 0.275042 -0.275042)
							(end 0.2032 -0.3048)
						)
						(arc
							(start -0.2032 -0.3048)
							(mid -0.275042 -0.275042)
							(end -0.3048 -0.2032)
						)
						(arc
							(start -0.3048 0.2032)
							(mid -0.275042 0.275042)
							(end -0.2032 0.3048)
						)
						(arc
							(start 0.2032 0.3048)
							(mid 0.275042 0.275042)
							(end 0.3048 0.2032)
						)
					)
					(width 0)
					(fill yes)
				)
			)
		)
	)
	(footprint ""
		(layer "F.Cu")
		(at 222.0468 -395.1478)
		(property "Reference" "PC1238"
			(at 0 0 0)
			(layer "F.SilkS")
			(hide yes)
			(effects
				(font
					(size 1.27 1.27)
				)
			)
		)
		(property "Value" "SCD01U50V2KX-1GP"
			(at 1.1811 -2.7051 0)
			(unlocked yes)
			(layer "F.Fab")
			(hide yes)
			(effects
				(font
					(size 1.016 1.016)
					(thickness 0.1524)
				)
			)
		)
		(property "Device Type" "C402H22"
			(at 1.1811 -4.2291 0)
			(unlocked yes)
			(layer "F.Fab")
			(hide yes)
			(effects
				(font
					(size 1.016 1.016)
					(thickness 0.1524)
				)
			)
		)
		(duplicate_pad_numbers_are_jumpers no)
		(fp_rect
			(start -0.4318 0.9525)
			(end 0.4318 -0.9525)
			(stroke
				(width 0)
				(type default)
			)
			(fill no)
			(layer "F.CrtYd")
		)
		(fp_rect
			(start -0.4318 0.9525)
			(end 0.4318 -0.9525)
			(stroke
				(width 0)
				(type default)
			)
			(fill no)
			(layer "F.Fab")
		)
		(pad "1" smd custom
			(at 0 -0.4445)
			(size 0.1524 0.1524)
			(layers "F.Cu" "F.Mask" "F.Paste")
			(net "P12V_SSD1")
			(options
				(clearance outline)
				(anchor circle)
			)
			(primitives
				(gr_poly
					(pts
						(arc
							(start 0.3048 -0.2032)
							(mid 0.275042 -0.275042)
							(end 0.2032 -0.3048)
						)
						(arc
							(start -0.2032 -0.3048)
							(mid -0.275042 -0.275042)
							(end -0.3048 -0.2032)
						)
						(arc
							(start -0.3048 0.2032)
							(mid -0.275042 0.275042)
							(end -0.2032 0.3048)
						)
						(arc
							(start 0.2032 0.3048)
							(mid 0.275042 0.275042)
							(end 0.3048 0.2032)
						)
					)
					(width 0)
					(fill yes)
				)
			)
		)
		(pad "2" smd custom
			(at 0 0.4445)
			(size 0.1524 0.1524)
			(layers "F.Cu" "F.Mask" "F.Paste")
			(net "GND")
			(options
				(clearance outline)
				(anchor circle)
			)
			(primitives
				(gr_poly
					(pts
						(arc
							(start 0.3048 -0.2032)
							(mid 0.275042 -0.275042)
							(end 0.2032 -0.3048)
						)
						(arc
							(start -0.2032 -0.3048)
							(mid -0.275042 -0.275042)
							(end -0.3048 -0.2032)
						)
						(arc
							(start -0.3048 0.2032)
							(mid -0.275042 0.275042)
							(end -0.2032 0.3048)
						)
						(arc
							(start 0.2032 0.3048)
							(mid 0.275042 0.275042)
							(end 0.3048 0.2032)
						)
					)
					(width 0)
					(fill yes)
				)
			)
		)
	)
	(footprint ""
		(layer "F.Cu")
		(at 88.011 -419.735 90)
		(property "Reference" "C131"
			(at 0 0 90)
			(layer "F.SilkS")
			(hide yes)
			(effects
				(font
					(size 1.27 1.27)
				)
			)
		)
		(property "Value" "SC1KP50V2KX-1GP"
			(at 1.1811 -2.7051 90)
			(unlocked yes)
			(layer "F.Fab")
			(hide yes)
			(effects
				(font
					(size 1.016 1.016)
					(thickness 0.1524)
				)
			)
		)
		(property "Device Type" "C402H22"
			(at 1.1811 -4.2291 90)
			(unlocked yes)
			(layer "F.Fab")
			(hide yes)
			(effects
				(font
					(size 1.016 1.016)
					(thickness 0.1524)
				)
			)
		)
		(duplicate_pad_numbers_are_jumpers no)
		(fp_rect
			(start -0.4318 0.9525)
			(end 0.4318 -0.9525)
			(stroke
				(width 0)
				(type default)
			)
			(fill no)
			(layer "F.CrtYd")
		)
		(fp_rect
			(start -0.4318 0.9525)
			(end 0.4318 -0.9525)
			(stroke
				(width 0)
				(type default)
			)
			(fill no)
			(layer "F.Fab")
		)
		(pad "1" smd custom
			(at 0 -0.4445 90)
			(size 0.1524 0.1524)
			(layers "F.Cu" "F.Mask" "F.Paste")
			(net "SSD_PRSNT10")
			(options
				(clearance outline)
				(anchor circle)
			)
			(primitives
				(gr_poly
					(pts
						(arc
							(start 0.3048 -0.2032)
							(mid 0.275042 -0.275042)
							(end 0.2032 -0.3048)
						)
						(arc
							(start -0.2032 -0.3048)
							(mid -0.275042 -0.275042)
							(end -0.3048 -0.2032)
						)
						(arc
							(start -0.3048 0.2032)
							(mid -0.275042 0.275042)
							(end -0.2032 0.3048)
						)
						(arc
							(start 0.2032 0.3048)
							(mid 0.275042 0.275042)
							(end 0.3048 0.2032)
						)
					)
					(width 0)
					(fill yes)
				)
			)
		)
		(pad "2" smd custom
			(at 0 0.4445 90)
			(size 0.1524 0.1524)
			(layers "F.Cu" "F.Mask" "F.Paste")
			(net "GND")
			(options
				(clearance outline)
				(anchor circle)
			)
			(primitives
				(gr_poly
					(pts
						(arc
							(start 0.3048 -0.2032)
							(mid 0.275042 -0.275042)
							(end 0.2032 -0.3048)
						)
						(arc
							(start -0.2032 -0.3048)
							(mid -0.275042 -0.275042)
							(end -0.3048 -0.2032)
						)
						(arc
							(start -0.3048 0.2032)
							(mid -0.275042 0.275042)
							(end -0.2032 0.3048)
						)
						(arc
							(start 0.2032 0.3048)
							(mid 0.275042 0.275042)
							(end 0.3048 0.2032)
						)
					)
					(width 0)
					(fill yes)
				)
			)
		)
	)
	(footprint ""
		(layer "F.Cu")
		(at 25.7556 -204.6478 90)
		(property "Reference" "R9858"
			(at 0 0 90)
			(layer "F.SilkS")
			(hide yes)
			(effects
				(font
					(size 1.27 1.27)
				)
			)
		)
		(property "Value" "2K2R5F-GP"
			(at 0 -8.9535 90)
			(unlocked yes)
			(layer "F.Fab")
			(hide yes)
			(effects
				(font
					(size 1.27 1.016)
					(thickness 0.1524)
				)
			)
		)
		(property "Device Type" "R805H24"
			(at 0 -10.6299 90)
			(unlocked yes)
			(layer "F.Fab")
			(hide yes)
			(effects
				(font
					(size 1.27 1.016)
					(thickness 0.1524)
				)
			)
		)
		(duplicate_pad_numbers_are_jumpers no)
		(fp_line
			(start 0.889 -1.7018)
			(end -0.889 -1.7018)
			(stroke
				(width 0.1524)
				(type default)
			)
			(layer "F.SilkS")
		)
		(fp_line
			(start 0.889 -1.7018)
			(end 0.889 -0.381)
			(stroke
				(width 0.1524)
				(type default)
			)
			(layer "F.SilkS")
		)
		(fp_line
			(start -0.889 -1.7018)
			(end -0.889 0.2794)
			(stroke
				(width 0.1524)
				(type default)
			)
			(layer "F.SilkS")
		)
		(fp_line
			(start -0.889 0.0762)
			(end -0.889 1.7018)
			(stroke
				(width 0.1524)
				(type default)
			)
			(layer "F.SilkS")
		)
		(fp_line
			(start 0.889 1.7018)
			(end 0.889 -0.508)
			(stroke
				(width 0.1524)
				(type default)
			)
			(layer "F.SilkS")
		)
		(fp_line
			(start -0.889 1.7018)
			(end 0.889 1.7018)
			(stroke
				(width 0.1524)
				(type default)
			)
			(layer "F.SilkS")
		)
		(fp_poly
			(pts
				(xy 0.9652 -1.778) (xy 0.9652 1.778) (xy -0.9652 1.778) (xy -0.9652 -1.778)
			)
			(stroke
				(width 0)
				(type default)
			)
			(fill no)
			(layer "F.CrtYd")
		)
		(fp_rect
			(start -0.9652 1.778)
			(end 0.9652 -1.778)
			(stroke
				(width 0)
				(type default)
			)
			(fill no)
			(layer "F.Fab")
		)
		(pad "1" smd rect
			(at 0 -0.9652 90)
			(size 1.397 1.143)
			(layers "F.Cu" "F.Mask" "F.Paste")
			(net "P12V_SSD12")
		)
		(pad "2" smd rect
			(at 0 0.9652 90)
			(size 1.397 1.143)
			(layers "F.Cu" "F.Mask" "F.Paste")
			(net "P12V_MOST12_GATE_D")
		)
	)
)
